(kicad_pcb
	(version 20260206)
	(generator "pcbnew")
	(generator_version "10.0")
	(general
		(thickness 1.6)
		(legacy_teardrops no)
	)
	(paper "A4")
	(title_block
		(title "peb — Lightning_PEB_BRD.brd")
		(comment 1 "Lightning (Wiwynn / Facebook NVMe JBOF) / footprints 2263-2271 of 2563")
	)
	(layers
		(0 "F.Cu" signal "TOP")
		(4 "In1.Cu" signal "L2GND")
		(6 "In2.Cu" signal "L3")
		(8 "In3.Cu" signal "L4VCC")
		(10 "In4.Cu" signal "L5VCC")
		(12 "In5.Cu" signal "L6")
		(14 "In6.Cu" signal "L7GND")
		(2 "B.Cu" signal "BOTTOM")
		(9 "F.Adhes" user "F.Adhesive")
		(11 "B.Adhes" user "B.Adhesive")
		(13 "F.Paste" user "Package Geometry/Pastemask Top")
		(15 "B.Paste" user "Package Geometry/Pastemask Bottom")
		(5 "F.SilkS" user "Ref Des/Silkscreen Top")
		(7 "B.SilkS" user "Ref Des/Silkscreen Bottom")
		(1 "F.Mask" user "Board Geometry/Soldermask Top")
		(3 "B.Mask" user "Board Geometry/Soldermask Bottom")
		(17 "Dwgs.User" user "User.Drawings")
		(19 "Cmts.User" user "User.Comments")
		(21 "Eco1.User" user "User.Eco1")
		(23 "Eco2.User" user "User.Eco2")
		(25 "Edge.Cuts" user "Board Geometry/Outline")
		(27 "Margin" user)
		(31 "F.CrtYd" user "Package Geometry/Place Bound Top")
		(29 "B.CrtYd" user "Package Geometry/Place Bound Bottom")
		(35 "F.Fab" user "Ref Des/Assembly Top")
		(33 "B.Fab" user "Ref Des/Assembly Bottom")
	)
	(footprint ""
		(layer "B.Cu")
		(at 270.18615 -12.401042 90)
		(property "Reference" "R2962"
			(at 0 0 90)
			(layer "B.SilkS")
			(hide yes)
			(effects
				(font
					(size 1.27 1.27)
				)
				(justify mirror)
			)
		)
		(property "Value" "0R2J-2-GP"
			(at -0.064008 -3.993896 90)
			(unlocked yes)
			(layer "B.Fab")
			(hide yes)
			(effects
				(font
					(size 1.016 1.016)
					(thickness 0.1524)
				)
				(justify mirror)
			)
		)
		(property "Device Type" "R402H16"
			(at -0.064008 -5.517896 90)
			(unlocked yes)
			(layer "B.Fab")
			(hide yes)
			(effects
				(font
					(size 1.016 1.016)
					(thickness 0.1524)
				)
				(justify mirror)
			)
		)
		(duplicate_pad_numbers_are_jumpers no)
		(fp_line
			(start 0.508 -0.9398)
			(end 0.508 0.9398)
			(stroke
				(width 0.1524)
				(type default)
			)
			(layer "B.SilkS")
		)
		(fp_line
			(start -0.508 -0.9398)
			(end 0.508 -0.9398)
			(stroke
				(width 0.1524)
				(type default)
			)
			(layer "B.SilkS")
		)
		(fp_rect
			(start 0.508 0.9398)
			(end -0.508 -0.9398)
			(stroke
				(width 0)
				(type default)
			)
			(fill no)
			(layer "B.CrtYd")
		)
		(fp_rect
			(start 0.508 0.9398)
			(end -0.508 -0.9398)
			(stroke
				(width 0)
				(type default)
			)
			(fill no)
			(layer "B.Fab")
		)
		(pad "1" smd custom
			(at 0 -0.4445 270)
			(size 0.1397 0.1397)
			(layers "B.Cu" "B.Mask" "B.Paste")
			(net "HOST5_RST_N")
			(options
				(clearance outline)
				(anchor circle)
			)
			(primitives
				(gr_poly
					(pts
						(arc
							(start -0.1778 0.2794)
							(mid -0.249642 0.249642)
							(end -0.2794 0.1778)
						)
						(arc
							(start -0.2794 -0.1778)
							(mid -0.249642 -0.249642)
							(end -0.1778 -0.2794)
						)
						(arc
							(start 0.1778 -0.2794)
							(mid 0.249642 -0.249642)
							(end 0.2794 -0.1778)
						)
						(arc
							(start 0.2794 0.1778)
							(mid 0.249642 0.249642)
							(end 0.1778 0.2794)
						)
					)
					(width 0)
					(fill yes)
				)
			)
		)
		(pad "2" smd custom
			(at 0 0.4445 270)
			(size 0.1397 0.1397)
			(layers "B.Cu" "B.Mask" "B.Paste")
			(net "HOST5_RST_N_C")
			(options
				(clearance outline)
				(anchor circle)
			)
			(primitives
				(gr_poly
					(pts
						(arc
							(start -0.1778 0.2794)
							(mid -0.249642 0.249642)
							(end -0.2794 0.1778)
						)
						(arc
							(start -0.2794 -0.1778)
							(mid -0.249642 -0.249642)
							(end -0.1778 -0.2794)
						)
						(arc
							(start 0.1778 -0.2794)
							(mid 0.249642 -0.249642)
							(end 0.2794 -0.1778)
						)
						(arc
							(start 0.2794 0.1778)
							(mid 0.249642 0.249642)
							(end 0.1778 0.2794)
						)
					)
					(width 0)
					(fill yes)
				)
			)
		)
	)
	(footprint ""
		(layer "B.Cu")
		(at 179.9844 -61.595)
		(property "Reference" "C586"
			(at 0 0 0)
			(layer "B.SilkS")
			(hide yes)
			(effects
				(font
					(size 1.27 1.27)
				)
				(justify mirror)
			)
		)
		(property "Value" "SC4D7U16V5KX-1-GP"
			(at 0.0762 -6.1214 0)
			(unlocked yes)
			(layer "B.Fab")
			(hide yes)
			(effects
				(font
					(size 1.016 1.016)
					(thickness 0.1524)
				)
				(justify mirror)
			)
		)
		(property "Device Type" "C805H56"
			(at 0.0762 -8.1534 0)
			(unlocked yes)
			(layer "B.Fab")
			(hide yes)
			(effects
				(font
					(size 1.016 1.016)
					(thickness 0.1524)
				)
				(justify mirror)
			)
		)
		(duplicate_pad_numbers_are_jumpers no)
		(fp_line
			(start -0.635 0)
			(end 0.635 0)
			(stroke
				(width 0.508)
				(type default)
			)
			(layer "B.SilkS")
		)
		(fp_rect
			(start 0.9652 1.778)
			(end -0.9652 -1.778)
			(stroke
				(width 0)
				(type default)
			)
			(fill no)
			(layer "B.CrtYd")
		)
		(fp_poly
			(pts
				(xy 0.9652 -1.778) (xy -0.9652 -1.778) (xy -0.9652 1.778) (xy 0.9652 1.778)
			)
			(stroke
				(width 0)
				(type default)
			)
			(fill no)
			(layer "B.Fab")
		)
		(pad "1" smd rect
			(at 0 -0.9652 180)
			(size 1.397 1.143)
			(layers "B.Cu" "B.Mask" "B.Paste")
			(net "DUT_AVD_PCIE")
		)
		(pad "2" smd rect
			(at 0 0.9652 180)
			(size 1.397 1.143)
			(layers "B.Cu" "B.Mask" "B.Paste")
			(net "GND")
		)
	)
	(footprint ""
		(layer "B.Cu")
		(at 310.007 -60.071 180)
		(property "Reference" "PG58"
			(at 0 0 0)
			(layer "B.SilkS")
			(hide yes)
			(effects
				(font
					(size 1.27 1.27)
				)
				(justify mirror)
			)
		)
		(property "Value" "GAP-CLOSE-PWR-3-GP"
			(at -0.0254 -6.5786 180)
			(unlocked yes)
			(layer "B.Fab")
			(hide yes)
			(effects
				(font
					(size 1.016 1.016)
					(thickness 0.1524)
				)
				(justify mirror)
			)
		)
		(property "Device Type" "GAP-CLOSE-PWR-3"
			(at -0.0254 -8.255 180)
			(unlocked yes)
			(layer "B.Fab")
			(hide yes)
			(effects
				(font
					(size 1.016 1.016)
					(thickness 0.1524)
				)
				(justify mirror)
			)
		)
		(duplicate_pad_numbers_are_jumpers no)
		(fp_rect
			(start 0.7112 0.4572)
			(end -0.7112 -0.4572)
			(stroke
				(width 0)
				(type default)
			)
			(fill no)
			(layer "B.CrtYd")
		)
		(fp_poly
			(pts
				(xy 0.7112 -0.4572) (xy -0.7112 -0.4572) (xy -0.7112 0.4572) (xy 0.7112 0.4572)
			)
			(stroke
				(width 0)
				(type default)
			)
			(fill no)
			(layer "B.Fab")
		)
		(pad "1" smd rect
			(at 0.3048 0)
			(size 0.6604 0.762)
			(layers "B.Cu" "B.Mask" "B.Paste")
			(net "DUT_VDD")
		)
		(pad "2" smd rect
			(at -0.3048 0)
			(size 0.6604 0.762)
			(layers "B.Cu" "B.Mask" "B.Paste")
			(net "P0V9_E")
		)
	)
	(footprint ""
		(layer "B.Cu")
		(at 249.6058 -37.9984 -90)
		(property "Reference" "TP297"
			(at 0 0 90)
			(layer "B.SilkS")
			(hide yes)
			(effects
				(font
					(size 1.27 1.27)
				)
				(justify mirror)
			)
		)
		(property "Value" "TPAD28-2-GP"
			(at 0.0127 -1.6637 270)
			(unlocked yes)
			(layer "B.Fab")
			(hide yes)
			(effects
				(font
					(size 1.016 1.016)
					(thickness 0.1524)
				)
				(justify mirror)
			)
		)
		(property "Device Type" "TPAD28"
			(at 0.0127 -3.1877 270)
			(unlocked yes)
			(layer "B.Fab")
			(hide yes)
			(effects
				(font
					(size 1.016 1.016)
					(thickness 0.1524)
				)
				(justify mirror)
			)
		)
		(duplicate_pad_numbers_are_jumpers no)
		(fp_poly
			(pts
				(arc
					(start 0 -0.3556)
					(mid 0 0.3556)
					(end 0 -0.3556)
				)
			)
			(stroke
				(width 0)
				(type default)
			)
			(fill no)
			(layer "B.CrtYd")
		)
		(fp_poly
			(pts
				(arc
					(start 0 -0.6096)
					(mid 0 0.6096)
					(end 0 -0.6096)
				)
			)
			(stroke
				(width 0)
				(type default)
			)
			(fill no)
			(layer "B.Fab")
		)
		(pad "1" smd circle
			(at 0 0 90)
			(size 0.7112 0.7112)
			(layers "B.Cu" "B.Mask" "B.Paste")
			(net "TWI_SRST#8")
		)
	)
	(footprint ""
		(layer "B.Cu")
		(at 124.079 -205.74)
		(property "Reference" "C8094"
			(at 0 0 0)
			(layer "B.SilkS")
			(hide yes)
			(effects
				(font
					(size 1.27 1.27)
				)
				(justify mirror)
			)
		)
		(property "Value" "SCD047U25V2KX-GP"
			(at -1.1811 -2.7051 0)
			(unlocked yes)
			(layer "B.Fab")
			(hide yes)
			(effects
				(font
					(size 1.016 1.016)
					(thickness 0.1524)
				)
				(justify mirror)
			)
		)
		(property "Device Type" "C402H22"
			(at -1.1811 -4.2291 0)
			(unlocked yes)
			(layer "B.Fab")
			(hide yes)
			(effects
				(font
					(size 1.016 1.016)
					(thickness 0.1524)
				)
				(justify mirror)
			)
		)
		(duplicate_pad_numbers_are_jumpers no)
		(fp_rect
			(start 0.4318 0.9525)
			(end -0.4318 -0.9525)
			(stroke
				(width 0)
				(type default)
			)
			(fill no)
			(layer "B.CrtYd")
		)
		(fp_rect
			(start 0.4318 0.9525)
			(end -0.4318 -0.9525)
			(stroke
				(width 0)
				(type default)
			)
			(fill no)
			(layer "B.Fab")
		)
		(pad "1" smd custom
			(at 0 -0.4445 180)
			(size 0.1524 0.1524)
			(layers "B.Cu" "B.Mask" "B.Paste")
			(net "P3V3_STBY")
			(options
				(clearance outline)
				(anchor circle)
			)
			(primitives
				(gr_poly
					(pts
						(arc
							(start 0.3048 0.2032)
							(mid 0.275042 0.275042)
							(end 0.2032 0.3048)
						)
						(arc
							(start -0.2032 0.3048)
							(mid -0.275042 0.275042)
							(end -0.3048 0.2032)
						)
						(arc
							(start -0.3048 -0.2032)
							(mid -0.275042 -0.275042)
							(end -0.2032 -0.3048)
						)
						(arc
							(start 0.2032 -0.3048)
							(mid 0.275042 -0.275042)
							(end 0.3048 -0.2032)
						)
					)
					(width 0)
					(fill yes)
				)
			)
		)
		(pad "2" smd custom
			(at 0 0.4445 180)
			(size 0.1524 0.1524)
			(layers "B.Cu" "B.Mask" "B.Paste")
			(net "GND")
			(options
				(clearance outline)
				(anchor circle)
			)
			(primitives
				(gr_poly
					(pts
						(arc
							(start 0.3048 0.2032)
							(mid 0.275042 0.275042)
							(end 0.2032 0.3048)
						)
						(arc
							(start -0.2032 0.3048)
							(mid -0.275042 0.275042)
							(end -0.3048 0.2032)
						)
						(arc
							(start -0.3048 -0.2032)
							(mid -0.275042 -0.275042)
							(end -0.2032 -0.3048)
						)
						(arc
							(start 0.2032 -0.3048)
							(mid 0.275042 -0.275042)
							(end 0.3048 -0.2032)
						)
					)
					(width 0)
					(fill yes)
				)
			)
		)
	)
	(footprint ""
		(layer "B.Cu")
		(at 63.754 -126.9746)
		(property "Reference" "R420"
			(at 0 0 0)
			(layer "B.SilkS")
			(hide yes)
			(effects
				(font
					(size 1.27 1.27)
				)
				(justify mirror)
			)
		)
		(property "Value" "10KR2F-2-GP"
			(at -0.064008 -3.993896 0)
			(unlocked yes)
			(layer "B.Fab")
			(hide yes)
			(effects
				(font
					(size 1.016 1.016)
					(thickness 0.1524)
				)
				(justify mirror)
			)
		)
		(property "Device Type" "R402H16"
			(at -0.064008 -5.517896 0)
			(unlocked yes)
			(layer "B.Fab")
			(hide yes)
			(effects
				(font
					(size 1.016 1.016)
					(thickness 0.1524)
				)
				(justify mirror)
			)
		)
		(duplicate_pad_numbers_are_jumpers no)
		(fp_line
			(start -0.508 -0.9398)
			(end 0.508 -0.9398)
			(stroke
				(width 0.1524)
				(type default)
			)
			(layer "B.SilkS")
		)
		(fp_line
			(start 0.508 -0.9398)
			(end 0.508 0.9398)
			(stroke
				(width 0.1524)
				(type default)
			)
			(layer "B.SilkS")
		)
		(fp_rect
			(start 0.508 0.9398)
			(end -0.508 -0.9398)
			(stroke
				(width 0)
				(type default)
			)
			(fill no)
			(layer "B.CrtYd")
		)
		(fp_rect
			(start 0.508 0.9398)
			(end -0.508 -0.9398)
			(stroke
				(width 0)
				(type default)
			)
			(fill no)
			(layer "B.Fab")
		)
		(pad "1" smd custom
			(at 0 -0.4445 180)
			(size 0.1397 0.1397)
			(layers "B.Cu" "B.Mask" "B.Paste")
			(net "P3V3_STBY")
			(options
				(clearance outline)
				(anchor circle)
			)
			(primitives
				(gr_poly
					(pts
						(arc
							(start -0.1778 0.2794)
							(mid -0.249642 0.249642)
							(end -0.2794 0.1778)
						)
						(arc
							(start -0.2794 -0.1778)
							(mid -0.249642 -0.249642)
							(end -0.1778 -0.2794)
						)
						(arc
							(start 0.1778 -0.2794)
							(mid 0.249642 -0.249642)
							(end 0.2794 -0.1778)
						)
						(arc
							(start 0.2794 0.1778)
							(mid 0.249642 0.249642)
							(end 0.1778 0.2794)
						)
					)
					(width 0)
					(fill yes)
				)
			)
		)
		(pad "2" smd custom
			(at 0 0.4445 180)
			(size 0.1397 0.1397)
			(layers "B.Cu" "B.Mask" "B.Paste")
			(net "BMC_TXD5")
			(options
				(clearance outline)
				(anchor circle)
			)
			(primitives
				(gr_poly
					(pts
						(arc
							(start -0.1778 0.2794)
							(mid -0.249642 0.249642)
							(end -0.2794 0.1778)
						)
						(arc
							(start -0.2794 -0.1778)
							(mid -0.249642 -0.249642)
							(end -0.1778 -0.2794)
						)
						(arc
							(start 0.1778 -0.2794)
							(mid 0.249642 -0.249642)
							(end 0.2794 -0.1778)
						)
						(arc
							(start 0.2794 0.1778)
							(mid 0.249642 0.249642)
							(end 0.1778 0.2794)
						)
					)
					(width 0)
					(fill yes)
				)
			)
		)
	)
	(footprint ""
		(layer "B.Cu")
		(at 20.955 -128.651 90)
		(property "Reference" "R361"
			(at 0 0 90)
			(layer "B.SilkS")
			(hide yes)
			(effects
				(font
					(size 1.27 1.27)
				)
				(justify mirror)
			)
		)
		(property "Value" "3K3R2F-2-GP"
			(at -0.064008 -3.993896 90)
			(unlocked yes)
			(layer "B.Fab")
			(hide yes)
			(effects
				(font
					(size 1.016 1.016)
					(thickness 0.1524)
				)
				(justify mirror)
			)
		)
		(property "Device Type" "R402H16"
			(at -0.064008 -5.517896 90)
			(unlocked yes)
			(layer "B.Fab")
			(hide yes)
			(effects
				(font
					(size 1.016 1.016)
					(thickness 0.1524)
				)
				(justify mirror)
			)
		)
		(duplicate_pad_numbers_are_jumpers no)
		(fp_line
			(start 0.508 -0.9398)
			(end 0.508 0.9398)
			(stroke
				(width 0.1524)
				(type default)
			)
			(layer "B.SilkS")
		)
		(fp_line
			(start -0.508 -0.9398)
			(end 0.508 -0.9398)
			(stroke
				(width 0.1524)
				(type default)
			)
			(layer "B.SilkS")
		)
		(fp_rect
			(start 0.508 0.9398)
			(end -0.508 -0.9398)
			(stroke
				(width 0)
				(type default)
			)
			(fill no)
			(layer "B.CrtYd")
		)
		(fp_rect
			(start 0.508 0.9398)
			(end -0.508 -0.9398)
			(stroke
				(width 0)
				(type default)
			)
			(fill no)
			(layer "B.Fab")
		)
		(pad "1" smd custom
			(at 0 -0.4445 270)
			(size 0.1397 0.1397)
			(layers "B.Cu" "B.Mask" "B.Paste")
			(net "P3V3_STBY")
			(options
				(clearance outline)
				(anchor circle)
			)
			(primitives
				(gr_poly
					(pts
						(arc
							(start -0.1778 0.2794)
							(mid -0.249642 0.249642)
							(end -0.2794 0.1778)
						)
						(arc
							(start -0.2794 -0.1778)
							(mid -0.249642 -0.249642)
							(end -0.1778 -0.2794)
						)
						(arc
							(start 0.1778 -0.2794)
							(mid 0.249642 -0.249642)
							(end 0.2794 -0.1778)
						)
						(arc
							(start 0.2794 0.1778)
							(mid 0.249642 0.249642)
							(end 0.1778 0.2794)
						)
					)
					(width 0)
					(fill yes)
				)
			)
		)
		(pad "2" smd custom
			(at 0 0.4445 270)
			(size 0.1397 0.1397)
			(layers "B.Cu" "B.Mask" "B.Paste")
			(net "ROMA21")
			(options
				(clearance outline)
				(anchor circle)
			)
			(primitives
				(gr_poly
					(pts
						(arc
							(start -0.1778 0.2794)
							(mid -0.249642 0.249642)
							(end -0.2794 0.1778)
						)
						(arc
							(start -0.2794 -0.1778)
							(mid -0.249642 -0.249642)
							(end -0.1778 -0.2794)
						)
						(arc
							(start 0.1778 -0.2794)
							(mid 0.249642 -0.249642)
							(end 0.2794 -0.1778)
						)
						(arc
							(start 0.2794 0.1778)
							(mid 0.249642 0.249642)
							(end 0.1778 0.2794)
						)
					)
					(width 0)
					(fill yes)
				)
			)
		)
	)
	(footprint ""
		(layer "B.Cu")
		(at 252.603 -42.994072 -90)
		(property "Reference" "C615"
			(at 0 0 90)
			(layer "B.SilkS")
			(hide yes)
			(effects
				(font
					(size 1.27 1.27)
				)
				(justify mirror)
			)
		)
		(property "Value" "SCD1U16V1KX-1-GP"
			(at 2.8321 -1.7399 270)
			(unlocked yes)
			(layer "B.Fab")
			(hide yes)
			(effects
				(font
					(size 1.016 1.016)
					(thickness 0.1524)
				)
				(justify mirror)
			)
		)
		(property "Device Type" "C0201H13"
			(at 2.8321 -3.2639 270)
			(unlocked yes)
			(layer "B.Fab")
			(hide yes)
			(effects
				(font
					(size 1.016 1.016)
					(thickness 0.1524)
				)
				(justify mirror)
			)
		)
		(duplicate_pad_numbers_are_jumpers no)
		(fp_rect
			(start 0.2794 0.6477)
			(end -0.2794 -0.6477)
			(stroke
				(width 0)
				(type default)
			)
			(fill no)
			(layer "B.CrtYd")
		)
		(fp_rect
			(start 0.2794 0.6477)
			(end -0.2794 -0.6477)
			(stroke
				(width 0)
				(type default)
			)
			(fill no)
			(layer "B.Fab")
		)
		(pad "1" smd custom
			(at 0 -0.2794 90)
			(size 0.0762 0.0762)
			(layers "B.Cu" "B.Mask" "B.Paste")
			(net "DUT_AVD_PCIE")
			(options
				(clearance outline)
				(anchor circle)
			)
			(primitives
				(gr_poly
					(pts
						(arc
							(start 0.1524 0.127)
							(mid 0.137521 0.162921)
							(end 0.1016 0.1778)
						)
						(arc
							(start -0.1016 0.1778)
							(mid -0.137521 0.162921)
							(end -0.1524 0.127)
						)
						(arc
							(start -0.1524 -0.127)
							(mid -0.137521 -0.162921)
							(end -0.1016 -0.1778)
						)
						(arc
							(start 0.1016 -0.1778)
							(mid 0.137521 -0.162921)
							(end 0.1524 -0.127)
						)
					)
					(width 0)
					(fill yes)
				)
			)
		)
		(pad "2" smd custom
			(at 0 0.2794 90)
			(size 0.0762 0.0762)
			(layers "B.Cu" "B.Mask" "B.Paste")
			(net "GND")
			(options
				(clearance outline)
				(anchor circle)
			)
			(primitives
				(gr_poly
					(pts
						(arc
							(start 0.1524 0.127)
							(mid 0.137521 0.162921)
							(end 0.1016 0.1778)
						)
						(arc
							(start -0.1016 0.1778)
							(mid -0.137521 0.162921)
							(end -0.1524 0.127)
						)
						(arc
							(start -0.1524 -0.127)
							(mid -0.137521 -0.162921)
							(end -0.1016 -0.1778)
						)
						(arc
							(start 0.1016 -0.1778)
							(mid 0.137521 -0.162921)
							(end 0.1524 -0.127)
						)
					)
					(width 0)
					(fill yes)
				)
			)
		)
	)
	(footprint ""
		(layer "B.Cu")
		(at 130.556 -202.565)
		(property "Reference" "R140"
			(at 0 0 0)
			(layer "B.SilkS")
			(hide yes)
			(effects
				(font
					(size 1.27 1.27)
				)
				(justify mirror)
			)
		)
		(property "Value" "4K7R2F-GP"
			(at -0.064008 -3.993896 0)
			(unlocked yes)
			(layer "B.Fab")
			(hide yes)
			(effects
				(font
					(size 1.016 1.016)
					(thickness 0.1524)
				)
				(justify mirror)
			)
		)
		(property "Device Type" "R402H16"
			(at -0.064008 -5.517896 0)
			(unlocked yes)
			(layer "B.Fab")
			(hide yes)
			(effects
				(font
					(size 1.016 1.016)
					(thickness 0.1524)
				)
				(justify mirror)
			)
		)
		(duplicate_pad_numbers_are_jumpers no)
		(fp_line
			(start -0.508 -0.9398)
			(end 0.508 -0.9398)
			(stroke
				(width 0.1524)
				(type default)
			)
			(layer "B.SilkS")
		)
		(fp_line
			(start 0.508 -0.9398)
			(end 0.508 0.9398)
			(stroke
				(width 0.1524)
				(type default)
			)
			(layer "B.SilkS")
		)
		(fp_rect
			(start 0.508 0.9398)
			(end -0.508 -0.9398)
			(stroke
				(width 0)
				(type default)
			)
			(fill no)
			(layer "B.CrtYd")
		)
		(fp_rect
			(start 0.508 0.9398)
			(end -0.508 -0.9398)
			(stroke
				(width 0)
				(type default)
			)
			(fill no)
			(layer "B.Fab")
		)
		(pad "1" smd custom
			(at 0 -0.4445 180)
			(size 0.1397 0.1397)
			(layers "B.Cu" "B.Mask" "B.Paste")
			(net "BMC_SSD_RST#0_A2")
			(options
				(clearance outline)
				(anchor circle)
			)
			(primitives
				(gr_poly
					(pts
						(arc
							(start -0.1778 0.2794)
							(mid -0.249642 0.249642)
							(end -0.2794 0.1778)
						)
						(arc
							(start -0.2794 -0.1778)
							(mid -0.249642 -0.249642)
							(end -0.1778 -0.2794)
						)
						(arc
							(start 0.1778 -0.2794)
							(mid 0.249642 -0.249642)
							(end 0.2794 -0.1778)
						)
						(arc
							(start 0.2794 0.1778)
							(mid 0.249642 0.249642)
							(end 0.1778 0.2794)
						)
					)
					(width 0)
					(fill yes)
				)
			)
		)
		(pad "2" smd custom
			(at 0 0.4445 180)
			(size 0.1397 0.1397)
			(layers "B.Cu" "B.Mask" "B.Paste")
			(net "P3V3_STBY")
			(options
				(clearance outline)
				(anchor circle)
			)
			(primitives
				(gr_poly
					(pts
						(arc
							(start -0.1778 0.2794)
							(mid -0.249642 0.249642)
							(end -0.2794 0.1778)
						)
						(arc
							(start -0.2794 -0.1778)
							(mid -0.249642 -0.249642)
							(end -0.1778 -0.2794)
						)
						(arc
							(start 0.1778 -0.2794)
							(mid 0.249642 -0.249642)
							(end 0.2794 -0.1778)
						)
						(arc
							(start 0.2794 0.1778)
							(mid 0.249642 0.249642)
							(end 0.1778 0.2794)
						)
					)
					(width 0)
					(fill yes)
				)
			)
		)
	)
)
